(kicad_pcb
	(version 20260206)
	(generator "pcbnew")
	(generator_version "10.0")
	(general
		(thickness 1.6)
		(legacy_teardrops no)
	)
	(paper "A4")
	(title_block
		(title "01162023_DA0F0TEBIF0_F0T_Expander_BD_F_brd_V02_OCP.brd")
		(comment 1 "Grand Teton / footprints 5574-5579 of 9728")
	)
	(layers
		(0 "F.Cu" signal "TOP")
		(4 "In1.Cu" signal "GND")
		(6 "In2.Cu" signal "VCC")
		(8 "In3.Cu" signal "VCC1")
		(10 "In4.Cu" signal "GND1")
		(12 "In5.Cu" signal "IN1")
		(14 "In6.Cu" signal "GND2")
		(16 "In7.Cu" signal "IN2")
		(18 "In8.Cu" signal "GND3")
		(20 "In9.Cu" signal "IN3")
		(22 "In10.Cu" signal "GND4")
		(24 "In11.Cu" signal "IN4")
		(26 "In12.Cu" signal "GND5")
		(28 "In13.Cu" signal "IN5")
		(30 "In14.Cu" signal "GND6")
		(32 "In15.Cu" signal "IN6")
		(34 "In16.Cu" signal "GND7")
		(2 "B.Cu" signal "BOTTOM")
		(9 "F.Adhes" user "F.Adhesive")
		(11 "B.Adhes" user "B.Adhesive")
		(13 "F.Paste" user "Package Geometry/Pastemask Top")
		(15 "B.Paste" user "Package Geometry/Pastemask Bottom")
		(5 "F.SilkS" user "Ref Des/Silkscreen Top")
		(7 "B.SilkS" user "Ref Des/Silkscreen Bottom")
		(1 "F.Mask" user "Board Geometry/Soldermask Top")
		(3 "B.Mask" user "Board Geometry/Soldermask Bottom")
		(17 "Dwgs.User" user "User.Drawings")
		(19 "Cmts.User" user "User.Comments")
		(21 "Eco1.User" user "User.Eco1")
		(23 "Eco2.User" user "User.Eco2")
		(25 "Edge.Cuts" user "Board Geometry/Outline")
		(27 "Margin" user)
		(31 "F.CrtYd" user "Package Geometry/Place Bound Top")
		(29 "B.CrtYd" user "Package Geometry/Place Bound Bottom")
		(35 "F.Fab" user "Ref Des/Assembly Top")
		(33 "B.Fab" user "Ref Des/Assembly Bottom")
	)
	(footprint ""
		(layer "F.Cu")
		(at 399.5928 -86.7664 180)
		(property "Reference" "R6265"
			(at 0 0 180)
			(layer "F.SilkS")
			(hide yes)
			(effects
				(font
					(size 1.27 1.27)
				)
			)
		)
		(property "Value" ""
			(at 0 0 180)
			(layer "F.Fab")
			(effects
				(font
					(size 1.27 1.27)
				)
			)
		)
		(duplicate_pad_numbers_are_jumpers no)
		(fp_line
			(start 0.7874 0.4064)
			(end -0.7874 0.4064)
			(stroke
				(width 0.1524)
				(type default)
			)
			(layer "F.SilkS")
		)
		(fp_line
			(start 0.7874 -0.4064)
			(end 0.7874 0.4064)
			(stroke
				(width 0.1524)
				(type default)
			)
			(layer "F.SilkS")
		)
		(fp_line
			(start -0.7874 0.4064)
			(end -0.7874 -0.4064)
			(stroke
				(width 0.1524)
				(type default)
			)
			(layer "F.SilkS")
		)
		(fp_line
			(start -0.7874 -0.4064)
			(end 0.7874 -0.4064)
			(stroke
				(width 0.1524)
				(type default)
			)
			(layer "F.SilkS")
		)
		(fp_line
			(start 0.67945 0.3048)
			(end 0.120396 0.3048)
			(stroke
				(width 0.1)
				(type default)
			)
			(layer "F.Fab")
		)
		(fp_line
			(start 0.67945 -0.3048)
			(end 0.67945 0.3048)
			(stroke
				(width 0.1)
				(type default)
			)
			(layer "F.Fab")
		)
		(fp_line
			(start 0.12065 -0.2794)
			(end 0.12065 -0.3048)
			(stroke
				(width 0.1)
				(type default)
			)
			(layer "F.Fab")
		)
		(fp_line
			(start 0.12065 -0.3048)
			(end 0.67945 -0.3048)
			(stroke
				(width 0.1)
				(type default)
			)
			(layer "F.Fab")
		)
		(fp_line
			(start 0.120396 0.3048)
			(end 0.120396 0.2794)
			(stroke
				(width 0.1)
				(type default)
			)
			(layer "F.Fab")
		)
		(fp_line
			(start 0.120396 0.2794)
			(end -0.12065 0.2794)
			(stroke
				(width 0.1)
				(type default)
			)
			(layer "F.Fab")
		)
		(fp_line
			(start -0.12065 0.3048)
			(end -0.67945 0.3048)
			(stroke
				(width 0.1)
				(type default)
			)
			(layer "F.Fab")
		)
		(fp_line
			(start -0.12065 0.2794)
			(end -0.12065 0.3048)
			(stroke
				(width 0.1)
				(type default)
			)
			(layer "F.Fab")
		)
		(fp_line
			(start -0.12065 -0.2794)
			(end 0.12065 -0.2794)
			(stroke
				(width 0.1)
				(type default)
			)
			(layer "F.Fab")
		)
		(fp_line
			(start -0.12065 -0.305054)
			(end -0.12065 -0.2794)
			(stroke
				(width 0.1)
				(type default)
			)
			(layer "F.Fab")
		)
		(fp_line
			(start -0.67945 0.3048)
			(end -0.67945 -0.305054)
			(stroke
				(width 0.1)
				(type default)
			)
			(layer "F.Fab")
		)
		(fp_line
			(start -0.67945 -0.305054)
			(end -0.12065 -0.305054)
			(stroke
				(width 0.1)
				(type default)
			)
			(layer "F.Fab")
		)
		(pad "1" smd circle
			(at -0.40005 0 180)
			(size 0 0)
			(layers "F.Cu" "F.Mask" "F.Paste")
			(net "CLK_ISO_EN")
		)
		(pad "2" smd circle
			(at 0.40005 0 180)
			(size 0 0)
			(layers "F.Cu" "F.Mask" "F.Paste")
			(net "P3V3_AUX")
		)
	)
	(footprint ""
		(layer "F.Cu")
		(at 415.501328 -55.78475 -90)
		(property "Reference" "PD122"
			(at 4.07035 2.140458 90)
			(unlocked yes)
			(layer "F.SilkS")
			(effects
				(font
					(size 0.7874 0.5842)
					(thickness 0.1524)
				)
				(justify left)
			)
		)
		(property "Value" ""
			(at 0 0 270)
			(layer "F.Fab")
			(effects
				(font
					(size 1.27 1.27)
				)
			)
		)
		(duplicate_pad_numbers_are_jumpers no)
		(fp_line
			(start -3.400044 1.459992)
			(end -3.400044 -1.459992)
			(stroke
				(width 0.1524)
				(type default)
			)
			(layer "F.SilkS")
		)
		(fp_line
			(start 4.107942 1.459992)
			(end -3.400044 1.459992)
			(stroke
				(width 0.1524)
				(type default)
			)
			(layer "F.SilkS")
		)
		(fp_line
			(start -3.400044 -1.459992)
			(end 4.107942 -1.459992)
			(stroke
				(width 0.1524)
				(type default)
			)
			(layer "F.SilkS")
		)
		(fp_line
			(start 4.107942 -1.459992)
			(end 4.107942 1.459992)
			(stroke
				(width 0.1524)
				(type default)
			)
			(layer "F.SilkS")
		)
		(fp_poly
			(pts
				(xy 4.107942 -1.459992) (xy 4.107942 1.459992) (xy 3.308096 1.459992) (xy 3.308096 -1.459992)
			)
			(stroke
				(width 0)
				(type default)
			)
			(fill yes)
			(layer "F.SilkS")
		)
		(fp_line
			(start -2.29997 1.459992)
			(end -2.29997 -1.459992)
			(stroke
				(width 0.1)
				(type default)
			)
			(layer "F.Fab")
		)
		(fp_line
			(start 2.29997 1.459992)
			(end -2.29997 1.459992)
			(stroke
				(width 0.1)
				(type default)
			)
			(layer "F.Fab")
		)
		(fp_line
			(start -2.29997 -1.459992)
			(end 2.29997 -1.459992)
			(stroke
				(width 0.1)
				(type default)
			)
			(layer "F.Fab")
		)
		(fp_line
			(start 2.29997 -1.459992)
			(end 2.29997 1.459992)
			(stroke
				(width 0.1)
				(type default)
			)
			(layer "F.Fab")
		)
		(fp_text user "-"
			(at 5.4102 0.29845 90)
			(unlocked yes)
			(layer "F.SilkS")
			(effects
				(font
					(size 1.905 1.4224)
					(thickness 0.1524)
				)
				(justify left)
			)
		)
		(fp_text user "+"
			(at -4.7752 -0.12065 270)
			(unlocked yes)
			(layer "F.SilkS")
			(effects
				(font
					(size 1.905 1.4224)
					(thickness 0.1524)
				)
				(justify left)
			)
		)
		(fp_text user "-"
			(at 5.4102 0.29845 90)
			(unlocked yes)
			(layer "F.Fab")
			(effects
				(font
					(size 1.905 1.4224)
					(thickness 0.1524)
				)
				(justify left)
			)
		)
		(fp_text user "+"
			(at -4.7752 -0.12065 270)
			(unlocked yes)
			(layer "F.Fab")
			(effects
				(font
					(size 1.905 1.4224)
					(thickness 0.1524)
				)
				(justify left)
			)
		)
		(pad "A" smd rect
			(at -1.999996 0)
			(size 1.7018 2.5146)
			(layers "F.Cu" "F.Mask" "F.Paste")
			(net "GND")
		)
		(pad "C" smd rect
			(at 1.999996 0)
			(size 1.7018 2.5146)
			(layers "F.Cu" "F.Mask" "F.Paste")
			(net "P12V_SSD14_R")
		)
	)
	(footprint ""
		(layer "F.Cu")
		(at 129.831084 -125.144784 180)
		(property "Reference" "PU50"
			(at 2.573274 -2.85115 0)
			(unlocked yes)
			(layer "F.SilkS")
			(effects
				(font
					(size 0.7874 0.5842)
					(thickness 0.1524)
				)
				(justify left)
			)
		)
		(property "Value" ""
			(at 0 0 180)
			(layer "F.Fab")
			(effects
				(font
					(size 1.27 1.27)
				)
			)
		)
		(duplicate_pad_numbers_are_jumpers no)
		(fp_line
			(start 1.943608 1.549908)
			(end -1.943608 1.549908)
			(stroke
				(width 0.1524)
				(type default)
			)
			(layer "F.SilkS")
		)
		(fp_line
			(start 1.943608 -1.549908)
			(end 1.943608 1.549908)
			(stroke
				(width 0.1524)
				(type default)
			)
			(layer "F.SilkS")
		)
		(fp_line
			(start -1.943608 1.549908)
			(end -1.943608 -1.549908)
			(stroke
				(width 0.1524)
				(type default)
			)
			(layer "F.SilkS")
		)
		(fp_line
			(start -1.943608 -1.549908)
			(end 1.943608 -1.549908)
			(stroke
				(width 0.1524)
				(type default)
			)
			(layer "F.SilkS")
		)
		(fp_poly
			(pts
				(xy -2.019808 -1.549908) (xy -1.257808 -1.549908) (xy -1.257808 -1.880108) (xy -2.019808 -1.880108)
			)
			(stroke
				(width 0)
				(type default)
			)
			(fill yes)
			(layer "F.SilkS")
		)
		(fp_line
			(start 1.549908 1.549908)
			(end -1.549908 1.549908)
			(stroke
				(width 0.1)
				(type default)
			)
			(layer "F.Fab")
		)
		(fp_line
			(start 1.549908 -1.549908)
			(end 1.549908 1.549908)
			(stroke
				(width 0.1)
				(type default)
			)
			(layer "F.Fab")
		)
		(fp_line
			(start -1.549908 1.549908)
			(end -1.549908 -1.549908)
			(stroke
				(width 0.1)
				(type default)
			)
			(layer "F.Fab")
		)
		(fp_line
			(start -1.549908 -1.549908)
			(end 1.549908 -1.549908)
			(stroke
				(width 0.1)
				(type default)
			)
			(layer "F.Fab")
		)
		(fp_poly
			(pts
				(xy -2.019808 -1.549908) (xy -1.257808 -1.549908) (xy -1.257808 -1.880108) (xy -2.019808 -1.880108)
			)
			(stroke
				(width 0)
				(type default)
			)
			(fill yes)
			(layer "F.Fab")
		)
		(pad "1" smd rect
			(at -1.500124 -1.249934 90)
			(size 0.2794 0.6096)
			(layers "F.Cu" "F.Mask" "F.Paste")
			(net "P3V3_NIC2")
		)
		(pad "2" smd rect
			(at -1.500124 -0.750062 90)
			(size 0.2794 0.6096)
			(layers "F.Cu" "F.Mask" "F.Paste")
			(net "P3V3_NIC2")
		)
		(pad "3" smd rect
			(at -1.500124 -0.249936 90)
			(size 0.2794 0.6096)
			(layers "F.Cu" "F.Mask" "F.Paste")
			(net "P3V3_NIC2")
		)
		(pad "4" smd rect
			(at -1.500124 0.249936 90)
			(size 0.2794 0.6096)
			(layers "F.Cu" "F.Mask" "F.Paste")
			(net "P3V3_NIC2")
		)
		(pad "5" smd rect
			(at -1.500124 0.750062 90)
			(size 0.2794 0.6096)
			(layers "F.Cu" "F.Mask" "F.Paste")
			(net "P3V3_NIC2")
		)
		(pad "6" smd rect
			(at -1.500124 1.249934 90)
			(size 0.2794 0.6096)
			(layers "F.Cu" "F.Mask" "F.Paste")
			(net "GND")
		)
		(pad "7" smd rect
			(at 1.500124 1.249934 90)
			(size 0.2794 0.6096)
			(layers "F.Cu" "F.Mask" "F.Paste")
			(net "P3V3_NIC2_SS")
		)
		(pad "8" smd rect
			(at 1.500124 0.750062 90)
			(size 0.2794 0.6096)
			(layers "F.Cu" "F.Mask" "F.Paste")
			(net "PWRGD_P3V3_NIC2")
		)
		(pad "9" smd rect
			(at 1.500124 0.249936 90)
			(size 0.2794 0.6096)
			(layers "F.Cu" "F.Mask" "F.Paste")
			(net "P3V3_NIC2_OCP")
		)
		(pad "10" smd rect
			(at 1.500124 -0.249936 90)
			(size 0.2794 0.6096)
			(layers "F.Cu" "F.Mask" "F.Paste")
			(net "P5V_AUX")
		)
		(pad "11" smd rect
			(at 1.500124 -0.750062 90)
			(size 0.2794 0.6096)
			(layers "F.Cu" "F.Mask" "F.Paste")
			(net "HP_NIC2_EN")
		)
		(pad "12" smd rect
			(at 1.500124 -1.249934 90)
			(size 0.2794 0.6096)
			(layers "F.Cu" "F.Mask" "F.Paste")
			(net "P3V3_AUX")
		)
		(pad "13" smd rect
			(at 0 0 180)
			(size 1.9812 2.7178)
			(layers "F.Cu" "F.Mask" "F.Paste")
			(net "P3V3_AUX")
		)
		(zone
			(layer "F.Cu")
			(hatch none 0.5)
			(connect_pads
				(clearance 0)
			)
			(min_thickness 0.25)
			(keepout
				(tracks not_allowed)
				(vias allowed)
				(pads allowed)
				(copperpour not_allowed)
				(footprints allowed)
			)
			(placement
				(enabled no)
				(sheetname "")
			)
			(fill
				(thermal_gap 0.5)
				(thermal_bridge_width 0.5)
				(island_removal_mode 0)
			)
			(polygon
				(pts
					(xy 128.688084 -123.595384) (xy 128.688084 -123.722384) (xy 128.688084 -126.694184) (xy 128.688084 -126.694692)
					(xy 130.974084 -126.694692) (xy 130.974084 -126.694184) (xy 130.974084 -126.567184) (xy 130.974084 -125.144784)
					(xy 130.872484 -125.144784) (xy 130.872484 -126.567184) (xy 128.789684 -126.567184) (xy 128.789684 -123.722384)
					(xy 130.872484 -123.722384) (xy 130.872484 -125.119384) (xy 130.974084 -125.119384) (xy 130.974084 -123.722384)
					(xy 130.974084 -123.595384) (xy 130.974084 -123.594876) (xy 128.688084 -123.594876)
				)
			)
		)
	)
	(footprint ""
		(layer "F.Cu")
		(at 366.247172 -55.63489 90)
		(property "Reference" "PC407"
			(at 0 0 90)
			(layer "F.SilkS")
			(hide yes)
			(effects
				(font
					(size 1.27 1.27)
				)
			)
		)
		(property "Value" ""
			(at 0 0 90)
			(layer "F.Fab")
			(effects
				(font
					(size 1.27 1.27)
				)
			)
		)
		(duplicate_pad_numbers_are_jumpers no)
		(fp_line
			(start 1.524 -0.762)
			(end 1.524 0.762)
			(stroke
				(width 0.1524)
				(type default)
			)
			(layer "F.SilkS")
		)
		(fp_line
			(start -1.524 -0.762)
			(end 1.524 -0.762)
			(stroke
				(width 0.1524)
				(type default)
			)
			(layer "F.SilkS")
		)
		(fp_line
			(start 1.524 0.762)
			(end -1.524 0.762)
			(stroke
				(width 0.1524)
				(type default)
			)
			(layer "F.SilkS")
		)
		(fp_line
			(start -1.524 0.762)
			(end -1.524 -0.762)
			(stroke
				(width 0.1524)
				(type default)
			)
			(layer "F.SilkS")
		)
		(fp_line
			(start 1.1049 -0.724916)
			(end -1.1049 -0.724916)
			(stroke
				(width 0.1)
				(type default)
			)
			(layer "F.Fab")
		)
		(fp_line
			(start -1.1049 -0.724916)
			(end -1.1049 0.724916)
			(stroke
				(width 0.1)
				(type default)
			)
			(layer "F.Fab")
		)
		(fp_line
			(start 1.1049 0.724916)
			(end 1.1049 -0.724916)
			(stroke
				(width 0.1)
				(type default)
			)
			(layer "F.Fab")
		)
		(fp_line
			(start -1.1049 0.724916)
			(end 1.1049 0.724916)
			(stroke
				(width 0.1)
				(type default)
			)
			(layer "F.Fab")
		)
		(pad "1" smd rect
			(at -0.889 0 270)
			(size 1.016 1.27)
			(layers "F.Cu" "F.Mask" "F.Paste")
			(net "P12V_SSD12_R")
		)
		(pad "2" smd rect
			(at 0.889 0 270)
			(size 1.016 1.27)
			(layers "F.Cu" "F.Mask" "F.Paste")
			(net "GND")
		)
	)
	(footprint ""
		(layer "F.Cu")
		(at 447.247264 -21.37156)
		(property "Reference" "C3980"
			(at 0 0 0)
			(layer "F.SilkS")
			(hide yes)
			(effects
				(font
					(size 1.27 1.27)
				)
			)
		)
		(property "Value" ""
			(at 0 0 0)
			(layer "F.Fab")
			(effects
				(font
					(size 1.27 1.27)
				)
			)
		)
		(duplicate_pad_numbers_are_jumpers no)
		(fp_line
			(start -0.7874 -0.4064)
			(end 0.7874 -0.4064)
			(stroke
				(width 0.1524)
				(type default)
			)
			(layer "F.SilkS")
		)
		(fp_line
			(start -0.7874 0.4064)
			(end -0.7874 -0.4064)
			(stroke
				(width 0.1524)
				(type default)
			)
			(layer "F.SilkS")
		)
		(fp_line
			(start 0.7874 -0.4064)
			(end 0.7874 0.4064)
			(stroke
				(width 0.1524)
				(type default)
			)
			(layer "F.SilkS")
		)
		(fp_line
			(start 0.7874 0.4064)
			(end -0.7874 0.4064)
			(stroke
				(width 0.1524)
				(type default)
			)
			(layer "F.SilkS")
		)
		(fp_line
			(start -0.67945 -0.305054)
			(end -0.12065 -0.305054)
			(stroke
				(width 0.1)
				(type default)
			)
			(layer "F.Fab")
		)
		(fp_line
			(start -0.67945 0.3048)
			(end -0.67945 -0.305054)
			(stroke
				(width 0.1)
				(type default)
			)
			(layer "F.Fab")
		)
		(fp_line
			(start -0.12065 -0.305054)
			(end -0.12065 -0.2794)
			(stroke
				(width 0.1)
				(type default)
			)
			(layer "F.Fab")
		)
		(fp_line
			(start -0.12065 -0.2794)
			(end 0.12065 -0.2794)
			(stroke
				(width 0.1)
				(type default)
			)
			(layer "F.Fab")
		)
		(fp_line
			(start -0.12065 0.2794)
			(end -0.12065 0.3048)
			(stroke
				(width 0.1)
				(type default)
			)
			(layer "F.Fab")
		)
		(fp_line
			(start -0.12065 0.3048)
			(end -0.67945 0.3048)
			(stroke
				(width 0.1)
				(type default)
			)
			(layer "F.Fab")
		)
		(fp_line
			(start 0.120396 0.2794)
			(end -0.12065 0.2794)
			(stroke
				(width 0.1)
				(type default)
			)
			(layer "F.Fab")
		)
		(fp_line
			(start 0.120396 0.3048)
			(end 0.120396 0.2794)
			(stroke
				(width 0.1)
				(type default)
			)
			(layer "F.Fab")
		)
		(fp_line
			(start 0.12065 -0.3048)
			(end 0.67945 -0.3048)
			(stroke
				(width 0.1)
				(type default)
			)
			(layer "F.Fab")
		)
		(fp_line
			(start 0.12065 -0.2794)
			(end 0.12065 -0.3048)
			(stroke
				(width 0.1)
				(type default)
			)
			(layer "F.Fab")
		)
		(fp_line
			(start 0.67945 -0.3048)
			(end 0.67945 0.3048)
			(stroke
				(width 0.1)
				(type default)
			)
			(layer "F.Fab")
		)
		(fp_line
			(start 0.67945 0.3048)
			(end 0.120396 0.3048)
			(stroke
				(width 0.1)
				(type default)
			)
			(layer "F.Fab")
		)
		(pad "1" smd circle
			(at -0.40005 0)
			(size 0 0)
			(layers "F.Cu" "F.Mask" "F.Paste")
			(net "P12V_SSD15")
		)
		(pad "2" smd circle
			(at 0.40005 0)
			(size 0 0)
			(layers "F.Cu" "F.Mask" "F.Paste")
			(net "GND")
		)
	)
	(footprint ""
		(layer "F.Cu")
		(at 92.050108 -306.074572 90)
		(property "Reference" "R1242"
			(at 0 0 90)
			(layer "F.SilkS")
			(hide yes)
			(effects
				(font
					(size 1.27 1.27)
				)
			)
		)
		(property "Value" ""
			(at 0 0 90)
			(layer "F.Fab")
			(effects
				(font
					(size 1.27 1.27)
				)
			)
		)
		(duplicate_pad_numbers_are_jumpers no)
		(fp_line
			(start 0.7874 -0.4064)
			(end 0.7874 0.4064)
			(stroke
				(width 0.1524)
				(type default)
			)
			(layer "F.SilkS")
		)
		(fp_line
			(start -0.7874 -0.4064)
			(end 0.7874 -0.4064)
			(stroke
				(width 0.1524)
				(type default)
			)
			(layer "F.SilkS")
		)
		(fp_line
			(start 0.7874 0.4064)
			(end -0.7874 0.4064)
			(stroke
				(width 0.1524)
				(type default)
			)
			(layer "F.SilkS")
		)
		(fp_line
			(start -0.7874 0.4064)
			(end -0.7874 -0.4064)
			(stroke
				(width 0.1524)
				(type default)
			)
			(layer "F.SilkS")
		)
		(fp_line
			(start -0.12065 -0.305054)
			(end -0.12065 -0.2794)
			(stroke
				(width 0.1)
				(type default)
			)
			(layer "F.Fab")
		)
		(fp_line
			(start -0.67945 -0.305054)
			(end -0.12065 -0.305054)
			(stroke
				(width 0.1)
				(type default)
			)
			(layer "F.Fab")
		)
		(fp_line
			(start 0.67945 -0.3048)
			(end 0.67945 0.3048)
			(stroke
				(width 0.1)
				(type default)
			)
			(layer "F.Fab")
		)
		(fp_line
			(start 0.12065 -0.3048)
			(end 0.67945 -0.3048)
			(stroke
				(width 0.1)
				(type default)
			)
			(layer "F.Fab")
		)
		(fp_line
			(start 0.12065 -0.2794)
			(end 0.12065 -0.3048)
			(stroke
				(width 0.1)
				(type default)
			)
			(layer "F.Fab")
		)
		(fp_line
			(start -0.12065 -0.2794)
			(end 0.12065 -0.2794)
			(stroke
				(width 0.1)
				(type default)
			)
			(layer "F.Fab")
		)
		(fp_line
			(start 0.120396 0.2794)
			(end -0.12065 0.2794)
			(stroke
				(width 0.1)
				(type default)
			)
			(layer "F.Fab")
		)
		(fp_line
			(start -0.12065 0.2794)
			(end -0.12065 0.3048)
			(stroke
				(width 0.1)
				(type default)
			)
			(layer "F.Fab")
		)
		(fp_line
			(start 0.67945 0.3048)
			(end 0.120396 0.3048)
			(stroke
				(width 0.1)
				(type default)
			)
			(layer "F.Fab")
		)
		(fp_line
			(start 0.120396 0.3048)
			(end 0.120396 0.2794)
			(stroke
				(width 0.1)
				(type default)
			)
			(layer "F.Fab")
		)
		(fp_line
			(start -0.12065 0.3048)
			(end -0.67945 0.3048)
			(stroke
				(width 0.1)
				(type default)
			)
			(layer "F.Fab")
		)
		(fp_line
			(start -0.67945 0.3048)
			(end -0.67945 -0.305054)
			(stroke
				(width 0.1)
				(type default)
			)
			(layer "F.Fab")
		)
		(pad "1" smd circle
			(at -0.40005 0 90)
			(size 0 0)
			(layers "F.Cu" "F.Mask" "F.Paste")
			(net "PEX0_SPARE6")
		)
		(pad "2" smd circle
			(at 0.40005 0 90)
			(size 0 0)
			(layers "F.Cu" "F.Mask" "F.Paste")
			(net "P1V8_PEX")
		)
	)
)
